#ISCELL
  mstr_misc dns *
  *
#ISCELL
  pure_quanta quanta_title_block_c *
  *
#ISCELL
  standard offpage *
  page185_i1
#CELL
  pure_quanta q_res *
  page185_i10
#ISCELL
  standard offpage *
  page185_i100
#ISCELL
  standard offpage *
  page185_i101
#CELL
  pure_quanta q_res *
  page185_i102
#CELL
  pure_quanta q_res *
  page185_i103
#ISCELL
  pure_quanta_power universal_gnd *
  page185_i104
#ISCELL
  pure_quanta_power universal_gnd *
  page185_i105
#ISCELL
  pure_quanta_power universal_gnd *
  page185_i106
#CELL
  pure_quanta q_res *
  page185_i107
#ISCELL
  standard offpage *
  page185_i108
#ISCELL
  standard offpage *
  page185_i109
#ISCELL
  pure_quanta_power vcc_core *
  page185_i11
#ISCELL
  standard offpage *
  page185_i110
#ISCELL
  standard offpage *
  page185_i111
#ISCELL
  standard offpage *
  page185_i112
#ISCELL
  pure_quanta_power universal_gnd *
  page185_i113
#CELL
  pure_quanta q_cap *
  page185_i114
#ISCELL
  pure_quanta_power universal_gnd *
  page185_i115
#CELL
  pure_quanta q_cap *
  page185_i116
#ISCELL
  standard offpage *
  page185_i117
#ISCELL
  standard offpage *
  page185_i118
#ISCELL
  standard offpage *
  page185_i119
#ISCELL
  pure_quanta_power universal_gnd *
  page185_i12
#ISCELL
  standard offpage *
  page185_i120
#ISCELL
  standard offpage *
  page185_i121
#ISCELL
  standard offpage *
  page185_i122
#ISCELL
  standard offpage *
  page185_i123
#ISCELL
  pure_quanta_power universal_gnd *
  page185_i124
#CELL
  pure_quanta q_cap *
  page185_i125
#ISCELL
  pure_quanta_power universal_gnd *
  page185_i126
#CELL
  pure_quanta q_cap *
  page185_i127
#ISCELL
  standard offpage *
  page185_i128
#CELL
  pure_quanta q_res *
  page185_i129
#CELL
  pure_quanta q_cap *
  page185_i13
#ISCELL
  pure_quanta_power vcc_core *
  page185_i130
#ISCELL
  pure_quanta_power vcc_core *
  page185_i131
#CELL
  pure_quanta q_cap *
  page185_i132
#CELL
  pure_quanta raa229620gnpha0 *
  page185_i133
#CELL
  pure_quanta q_res *
  page185_i135
#ISCELL
  pure_quanta_power universal_gnd *
  page185_i136
#CELL
  pure_quanta q_cap *
  page185_i137
#ISCELL
  pure_quanta_power universal_gnd *
  page185_i138
#CELL
  pure_quanta q_cap *
  page185_i139
#CELL
  pure_quanta q_res *
  page185_i14
#ISCELL
  pure_quanta_power universal_gnd *
  page185_i140
#CELL
  pure_quanta q_cap *
  page185_i141
#CELL
  pure_quanta q_res *
  page185_i142
#CELL
  pure_quanta q_res *
  page185_i143
#CELL
  pure_quanta q_res *
  page185_i144
#ISCELL
  standard offpage *
  page185_i15
#CELL
  pure_quanta mosfet_n *
  page185_i16
#CELL
  pure_quanta q_res *
  page185_i17
#CELL
  pure_quanta mosfet_pch_gds_esd_protected *
  page185_i18
#ISCELL
  pure_quanta_power universal_gnd *
  page185_i19
#CELL
  pure_quanta q_res *
  page185_i2
#CELL
  pure_quanta q_res *
  page185_i20
#ISCELL
  pure_quanta_power universal_gnd *
  page185_i21
#CELL
  pure_quanta q_cap *
  page185_i22
#CELL
  pure_quanta q_res *
  page185_i23
#ISCELL
  pure_quanta_power vcc_core *
  page185_i24
#ISCELL
  pure_quanta_power universal_gnd *
  page185_i25
#CELL
  pure_quanta q_res *
  page185_i27
#ISCELL
  pure_quanta_power vcc_core *
  page185_i28
#ISCELL
  pure_quanta_power vcc_core *
  page185_i29
#ISCELL
  pure_quanta_power universal_gnd *
  page185_i3
#ISCELL
  pure_quanta_power vcc_core *
  page185_i30
#ISCELL
  standard offpage *
  page185_i31
#ISCELL
  standard offpage *
  page185_i32
#ISCELL
  standard offpage *
  page185_i33
#ISCELL
  standard offpage *
  page185_i34
#ISCELL
  pure_quanta_power universal_gnd *
  page185_i35
#CELL
  pure_quanta q_res *
  page185_i36
#ISCELL
  standard offpage *
  page185_i37
#ISCELL
  standard offpage *
  page185_i38
#CELL
  pure_quanta q_res *
  page185_i39
#CELL
  pure_quanta q_res *
  page185_i4
#ISCELL
  pure_quanta_power vcc_core *
  page185_i40
#CELL
  pure_quanta q_res *
  page185_i41
#CELL
  pure_quanta q_res *
  page185_i42
#CELL
  pure_quanta q_res *
  page185_i43
#ISCELL
  pure_quanta_power vcc_core *
  page185_i44
#CELL
  pure_quanta q_res *
  page185_i45
#ISCELL
  pure_quanta_power universal_gnd *
  page185_i46
#CELL
  pure_quanta q_res *
  page185_i47
#CELL
  pure_quanta q_res *
  page185_i48
#ISCELL
  pure_quanta_power universal_gnd *
  page185_i49
#ISCELL
  pure_quanta_power universal_gnd *
  page185_i5
#ISCELL
  pure_quanta_power universal_gnd *
  page185_i50
#CELL
  pure_quanta q_cap *
  page185_i51
#CELL
  pure_quanta q_cap *
  page185_i52
#ISCELL
  pure_quanta_power universal_gnd *
  page185_i53
#CELL
  pure_quanta q_res *
  page185_i54
#ISCELL
  pure_quanta_power universal_gnd *
  page185_i55
#ISCELL
  pure_quanta_power universal_gnd *
  page185_i56
#CELL
  pure_quanta q_res *
  page185_i57
#CELL
  pure_quanta q_cap *
  page185_i58
#CELL
  pure_quanta q_res *
  page185_i59
#CELL
  pure_quanta q_res *
  page185_i6
#CELL
  pure_quanta q_cap *
  page185_i60
#ISCELL
  pure_quanta_power universal_gnd *
  page185_i61
#CELL
  pure_quanta q_cap *
  page185_i62
#ISCELL
  pure_quanta_power universal_gnd *
  page185_i63
#CELL
  pure_quanta q_cap *
  page185_i64
#ISCELL
  pure_quanta_power universal_gnd *
  page185_i65
#CELL
  pure_quanta q_cap *
  page185_i66
#CELL
  pure_quanta q_res *
  page185_i67
#CELL
  pure_quanta q_res *
  page185_i68
#CELL
  pure_quanta q_res *
  page185_i69
#ISCELL
  standard offpage *
  page185_i7
#CELL
  pure_quanta q_res *
  page185_i70
#ISCELL
  pure_quanta_power vcc_core *
  page185_i71
#ISCELL
  standard offpage *
  page185_i72
#ISCELL
  standard offpage *
  page185_i73
#ISCELL
  standard offpage *
  page185_i74
#ISCELL
  standard offpage *
  page185_i75
#ISCELL
  standard offpage *
  page185_i76
#ISCELL
  pure_quanta_power vcc_core *
  page185_i77
#CELL
  pure_quanta q_res *
  page185_i78
#CELL
  pure_quanta q_res *
  page185_i79
#ISCELL
  standard offpage *
  page185_i8
#CELL
  pure_quanta q_res *
  page185_i80
#CELL
  pure_quanta q_res *
  page185_i81
#CELL
  pure_quanta q_res *
  page185_i82
#CELL
  pure_quanta q_res *
  page185_i83
#CELL
  pure_quanta q_res *
  page185_i84
#CELL
  pure_quanta q_res *
  page185_i85
#CELL
  pure_quanta q_cap *
  page185_i86
#ISCELL
  pure_quanta_power universal_gnd *
  page185_i87
#CELL
  pure_quanta q_cap *
  page185_i88
#ISCELL
  pure_quanta_power universal_gnd *
  page185_i89
#ISCELL
  standard offpage *
  page185_i9
#ISCELL
  pure_quanta_power universal_gnd *
  page185_i90
#CELL
  pure_quanta q_cap *
  page185_i91
#ISCELL
  standard offpage *
  page185_i92
#ISCELL
  pure_quanta_power universal_gnd *
  page185_i93
#CELL
  pure_quanta q_cap *
  page185_i94
#ISCELL
  standard offpage *
  page185_i95
#ISCELL
  standard offpage *
  page185_i96
#ISCELL
  standard offpage *
  page185_i97
#ISCELL
  standard offpage *
  page185_i98
#ISCELL
  standard offpage *
  page185_i99
